(kicad_pcb
	(version 20260206)
	(generator "pcbnew")
	(generator_version "10.0")
	(general
		(thickness 1.6)
		(legacy_teardrops no)
	)
	(paper "A4")
	(title_block
		(title "Bryce Canyon_IOM_M2_16342-2_OCP.brd")
		(comment 1 "Bryce Canyon / footprints 16-21 of 1146")
	)
	(layers
		(0 "F.Cu" signal "TOP")
		(4 "In1.Cu" signal "L2GND")
		(6 "In2.Cu" signal "L3")
		(8 "In3.Cu" signal "L4VCC")
		(10 "In4.Cu" signal "L5VCC")
		(12 "In5.Cu" signal "L6")
		(14 "In6.Cu" signal "L7GND")
		(2 "B.Cu" signal "BOTTOM")
		(9 "F.Adhes" user "F.Adhesive")
		(11 "B.Adhes" user "B.Adhesive")
		(13 "F.Paste" user "Package Geometry/Pastemask Top")
		(15 "B.Paste" user "Package Geometry/Pastemask Bottom")
		(5 "F.SilkS" user "Ref Des/Silkscreen Top")
		(7 "B.SilkS" user "Ref Des/Silkscreen Bottom")
		(1 "F.Mask" user "Board Geometry/Soldermask Top")
		(3 "B.Mask" user "Board Geometry/Soldermask Bottom")
		(17 "Dwgs.User" user "User.Drawings")
		(19 "Cmts.User" user "User.Comments")
		(21 "Eco1.User" user "User.Eco1")
		(23 "Eco2.User" user "User.Eco2")
		(25 "Edge.Cuts" user "Board Geometry/Outline")
		(27 "Margin" user)
		(31 "F.CrtYd" user "Package Geometry/Place Bound Top")
		(29 "B.CrtYd" user "Package Geometry/Place Bound Bottom")
		(35 "F.Fab" user "Ref Des/Assembly Top")
		(33 "B.Fab" user "Ref Des/Assembly Bottom")
	)
	(footprint ""
		(layer "F.Cu")
		(at 170.754294 -138.635232 -135)
		(property "Reference" "VIA64"
			(at 0 0 225)
			(layer "F.SilkS")
			(hide yes)
			(effects
				(font
					(size 1.27 1.27)
				)
			)
		)
		(property "Value" "85OHM-8L-1D6MM-L16L18-GP"
			(at 4.064105 0.609655 225)
			(unlocked yes)
			(layer "F.Fab")
			(hide yes)
			(effects
				(font
					(size 1.016 1.016)
					(thickness 0.1524)
				)
			)
		)
		(property "Device Type" "VIA-PCIE-4P-368076"
			(at 4.064105 -0.914474 225)
			(unlocked yes)
			(layer "F.Fab")
			(hide yes)
			(effects
				(font
					(size 1.016 1.016)
					(thickness 0.1524)
				)
			)
		)
		(duplicate_pad_numbers_are_jumpers no)
		(fp_poly
			(pts
				(xy -1.841491 -0.381057) (xy 1.841509 -0.381058) (xy 1.841508 0.380942) (xy -1.841491 0.380942)
			)
			(stroke
				(width 0)
				(type default)
			)
			(fill no)
			(layer "F.CrtYd")
		)
		(fp_poly
			(pts
				(xy -1.841491 -0.381057) (xy 1.841509 -0.381058) (xy 1.841508 0.380942) (xy -1.841491 0.380942)
			)
			(stroke
				(width 0)
				(type default)
			)
			(fill no)
			(layer "F.Fab")
		)
		(pad "1" thru_hole circle
			(at -1.460499 0 225)
			(size 0.508 0.508)
			(drill 0.254)
			(layers "*.Cu" "*.Mask")
			(remove_unused_layers no)
			(net "GND")
			(clearance 0.127)
			(thermal_gap 0.127)
		)
		(pad "2" thru_hole circle
			(at -0.4445 0 225)
			(size 0.508 0.508)
			(drill 0.254)
			(layers "*.Cu" "*.Mask")
			(remove_unused_layers no)
			(net "PCIE_COMP_TO_IOM_15_DP")
			(clearance 0.127)
			(thermal_gap 0.127)
		)
		(pad "3" thru_hole circle
			(at 0.4445 0 225)
			(size 0.508 0.508)
			(drill 0.254)
			(layers "*.Cu" "*.Mask")
			(remove_unused_layers no)
			(net "PCIE_COMP_TO_IOM_15_DN")
			(clearance 0.127)
			(thermal_gap 0.127)
		)
		(pad "4" thru_hole circle
			(at 1.460499 0 225)
			(size 0.508 0.508)
			(drill 0.254)
			(layers "*.Cu" "*.Mask")
			(remove_unused_layers no)
			(net "GND")
			(clearance 0.127)
			(thermal_gap 0.127)
		)
	)
	(footprint ""
		(layer "F.Cu")
		(at 219.992956 -97.383346 180)
		(property "Reference" "U81"
			(at 0 0 180)
			(layer "F.SilkS")
			(hide yes)
			(effects
				(font
					(size 1.27 1.27)
				)
			)
		)
		(property "Value" "TPS53319DQPR-GP"
			(at 4.7498 -5.6896 180)
			(unlocked yes)
			(layer "F.Fab")
			(hide yes)
			(effects
				(font
					(size 1.016 1.016)
					(thickness 0.1524)
				)
			)
		)
		(property "Device Type" "QFN22G6050-G6133H60"
			(at 4.7498 -7.2136 180)
			(unlocked yes)
			(layer "F.Fab")
			(hide yes)
			(effects
				(font
					(size 1.016 1.016)
					(thickness 0.1524)
				)
			)
		)
		(duplicate_pad_numbers_are_jumpers no)
		(fp_line
			(start 3.556 3.5179)
			(end 3.556 2.2479)
			(stroke
				(width 0.1524)
				(type default)
			)
			(layer "F.SilkS")
		)
		(fp_line
			(start 2.286 3.5179)
			(end 3.556 3.5179)
			(stroke
				(width 0.1524)
				(type default)
			)
			(layer "F.SilkS")
		)
		(fp_line
			(start 1.500124 3.262122)
			(end 1.500124 4.024122)
			(stroke
				(width 0.1524)
				(type default)
			)
			(layer "F.SilkS")
		)
		(fp_line
			(start 0.500126 -3.262122)
			(end 0.500126 -3.770122)
			(stroke
				(width 0.1524)
				(type default)
			)
			(layer "F.SilkS")
		)
		(fp_line
			(start -0.999998 3.262122)
			(end -0.999998 3.770122)
			(stroke
				(width 0.1524)
				(type default)
			)
			(layer "F.SilkS")
		)
		(fp_line
			(start -1.999996 -3.262122)
			(end -1.999996 -4.024122)
			(stroke
				(width 0.1524)
				(type default)
			)
			(layer "F.SilkS")
		)
		(fp_line
			(start -2.286 -3.5179)
			(end -3.556 -3.5179)
			(stroke
				(width 0.1524)
				(type default)
			)
			(layer "F.SilkS")
		)
		(fp_line
			(start -3.556 3.5179)
			(end -2.286 3.5179)
			(stroke
				(width 0.1524)
				(type default)
			)
			(layer "F.SilkS")
		)
		(fp_line
			(start -3.556 2.2479)
			(end -3.556 3.5179)
			(stroke
				(width 0.1524)
				(type default)
			)
			(layer "F.SilkS")
		)
		(fp_line
			(start -3.556 -3.5179)
			(end -3.556 -2.2479)
			(stroke
				(width 0.1524)
				(type default)
			)
			(layer "F.SilkS")
		)
		(fp_poly
			(pts
				(xy 3.556 -3.5179) (xy 2.5273 -3.5179) (xy 3.556 -2.4892)
			)
			(stroke
				(width 0)
				(type default)
			)
			(fill yes)
			(layer "F.SilkS")
		)
		(fp_rect
			(start -2.9972 2.5019)
			(end 2.9972 -2.5019)
			(stroke
				(width 0)
				(type default)
			)
			(fill no)
			(layer "F.CrtYd")
		)
		(fp_poly
			(pts
				(xy 3.556 -2.5019) (xy -2.9972 -2.5019) (xy -2.9972 2.5019) (xy 2.9972 2.5019) (xy 2.9972 -2.4892)
				(xy 3.556 -2.4892) (xy 3.556 3.5179) (xy -3.556 3.5179) (xy -3.556 -3.5179) (xy 3.556 -3.5179)
			)
			(stroke
				(width 0)
				(type default)
			)
			(fill no)
			(layer "F.CrtYd")
		)
		(fp_rect
			(start -3.556 3.5179)
			(end 3.556 -3.5179)
			(stroke
				(width 0)
				(type default)
			)
			(fill no)
			(layer "F.Fab")
		)
		(pad "1" smd rect
			(at 2.500122 -2.449322 180)
			(size 0.3048 1.1176)
			(layers "F.Cu" "F.Mask" "F.Paste")
			(net "P3V3_M2_VFB")
		)
		(pad "2" smd rect
			(at 1.999996 -2.449322 180)
			(size 0.3048 1.1176)
			(layers "F.Cu" "F.Mask" "F.Paste")
			(net "P3V3_M2_EN")
		)
		(pad "3" smd rect
			(at 1.500124 -2.449322 180)
			(size 0.3048 1.1176)
			(layers "F.Cu" "F.Mask" "F.Paste")
			(net "IOM_FULL_PGOOD")
		)
		(pad "4" smd rect
			(at 0.999998 -2.449322 180)
			(size 0.3048 1.1176)
			(layers "F.Cu" "F.Mask" "F.Paste")
			(net "P3V3_M2_VBST")
		)
		(pad "5" smd rect
			(at 0.500126 -2.449322 180)
			(size 0.3048 1.1176)
			(layers "F.Cu" "F.Mask" "F.Paste")
			(net "AGND_P3V3_M2")
		)
		(pad "6" smd rect
			(at 0 -2.449322 180)
			(size 0.3048 1.1176)
			(layers "F.Cu" "F.Mask" "F.Paste")
			(net "P3V3_M2_LL")
		)
		(pad "7" smd rect
			(at -0.500126 -2.449322 180)
			(size 0.3048 1.1176)
			(layers "F.Cu" "F.Mask" "F.Paste")
			(net "P3V3_M2_LL")
		)
		(pad "8" smd rect
			(at -0.999998 -2.449322 180)
			(size 0.3048 1.1176)
			(layers "F.Cu" "F.Mask" "F.Paste")
			(net "P3V3_M2_LL")
		)
		(pad "9" smd rect
			(at -1.500124 -2.449322 180)
			(size 0.3048 1.1176)
			(layers "F.Cu" "F.Mask" "F.Paste")
			(net "P3V3_M2_LL")
		)
		(pad "10" smd rect
			(at -1.999996 -2.449322 180)
			(size 0.3048 1.1176)
			(layers "F.Cu" "F.Mask" "F.Paste")
			(net "P3V3_M2_LL")
		)
		(pad "11" smd rect
			(at -2.500122 -2.449322 180)
			(size 0.3048 1.1176)
			(layers "F.Cu" "F.Mask" "F.Paste")
			(net "P3V3_M2_LL")
		)
		(pad "12" smd rect
			(at -2.500122 2.449322 180)
			(size 0.3048 1.1176)
			(layers "F.Cu" "F.Mask" "F.Paste")
			(net "P12V_STBY_VIN_U81")
		)
		(pad "13" smd rect
			(at -1.999996 2.449322 180)
			(size 0.3048 1.1176)
			(layers "F.Cu" "F.Mask" "F.Paste")
			(net "P12V_STBY_VIN_U81")
		)
		(pad "14" smd rect
			(at -1.500124 2.449322 180)
			(size 0.3048 1.1176)
			(layers "F.Cu" "F.Mask" "F.Paste")
			(net "P12V_STBY_VIN_U81")
		)
		(pad "15" smd rect
			(at -0.999998 2.449322 180)
			(size 0.3048 1.1176)
			(layers "F.Cu" "F.Mask" "F.Paste")
			(net "P12V_STBY_VIN_U81")
		)
		(pad "16" smd rect
			(at -0.500126 2.449322 180)
			(size 0.3048 1.1176)
			(layers "F.Cu" "F.Mask" "F.Paste")
			(net "P12V_STBY_VIN_U81")
		)
		(pad "17" smd rect
			(at 0 2.449322 180)
			(size 0.3048 1.1176)
			(layers "F.Cu" "F.Mask" "F.Paste")
			(net "P12V_STBY_VIN_U81")
		)
		(pad "18" smd rect
			(at 0.500126 2.449322 180)
			(size 0.3048 1.1176)
			(layers "F.Cu" "F.Mask" "F.Paste")
			(net "P3V3_M2_VREG")
		)
		(pad "19" smd rect
			(at 0.999998 2.449322 180)
			(size 0.3048 1.1176)
			(layers "F.Cu" "F.Mask" "F.Paste")
			(net "P12V_STBY_VDD_U81")
		)
		(pad "20" smd rect
			(at 1.500124 2.449322 180)
			(size 0.3048 1.1176)
			(layers "F.Cu" "F.Mask" "F.Paste")
			(net "P3V3_M2_MODE")
		)
		(pad "21" smd rect
			(at 1.999996 2.449322 180)
			(size 0.3048 1.1176)
			(layers "F.Cu" "F.Mask" "F.Paste")
			(net "P3V3_M2_TRIP")
		)
		(pad "22" smd rect
			(at 2.500122 2.449322 180)
			(size 0.3048 1.1176)
			(layers "F.Cu" "F.Mask" "F.Paste")
			(net "P3V3_M2_RF")
		)
		(pad "23" smd custom
			(at 0 0 180)
			(size 0.83185 0.83185)
			(layers "F.Cu" "F.Mask" "F.Paste")
			(net "GND")
			(options
				(clearance outline)
				(anchor circle)
			)
			(primitives
				(gr_poly
					(pts
						(xy -2.7813 1.6637) (xy -2.7813 1.2954) (xy -3.048 1.2954) (xy -3.048 0.9525) (xy -2.7813 0.9525)
						(xy -2.7813 -0.9525) (xy -3.048 -0.9525) (xy -3.048 -1.2954) (xy -2.7813 -1.2954) (xy -2.7813 -1.6637)
						(xy 2.7813 -1.6637) (xy 2.7813 -1.2954) (xy 3.048 -1.2954) (xy 3.048 -0.9525) (xy 2.7813 -0.9525)
						(xy 2.7813 0.9525) (xy 3.048 0.9525) (xy 3.048 1.2954) (xy 2.7813 1.2954) (xy 2.7813 1.6637)
					)
					(width 0)
					(fill yes)
				)
			)
		)
	)
	(footprint ""
		(layer "F.Cu")
		(at 55.7784 -181.3306)
		(property "Reference" "C172"
			(at 0 0 0)
			(layer "F.SilkS")
			(hide yes)
			(effects
				(font
					(size 1.27 1.27)
				)
			)
		)
		(property "Value" "SC10U6D3V5KX-4GP"
			(at -0.0762 -6.1214 0)
			(unlocked yes)
			(layer "F.Fab")
			(hide yes)
			(effects
				(font
					(size 1.016 1.016)
					(thickness 0.1524)
				)
			)
		)
		(property "Device Type" "C805H58"
			(at -0.0762 -8.1534 0)
			(unlocked yes)
			(layer "F.Fab")
			(hide yes)
			(effects
				(font
					(size 1.016 1.016)
					(thickness 0.1524)
				)
			)
		)
		(duplicate_pad_numbers_are_jumpers no)
		(fp_line
			(start 0.635 0)
			(end -0.635 0)
			(stroke
				(width 0.508)
				(type default)
			)
			(layer "F.SilkS")
		)
		(fp_rect
			(start -0.9652 1.778)
			(end 0.9652 -1.778)
			(stroke
				(width 0)
				(type default)
			)
			(fill no)
			(layer "F.CrtYd")
		)
		(fp_poly
			(pts
				(xy -0.9652 -1.778) (xy 0.9652 -1.778) (xy 0.9652 1.778) (xy -0.9652 1.778)
			)
			(stroke
				(width 0)
				(type default)
			)
			(fill no)
			(layer "F.Fab")
		)
		(pad "1" smd rect
			(at 0 -0.9652)
			(size 1.397 1.143)
			(layers "F.Cu" "F.Mask" "F.Paste")
			(net "P3V3_STBY_OUT")
		)
		(pad "2" smd rect
			(at 0 0.9652)
			(size 1.397 1.143)
			(layers "F.Cu" "F.Mask" "F.Paste")
			(net "GND")
		)
	)
	(footprint ""
		(layer "F.Cu")
		(at 209.186272 -94.238826 -90)
		(property "Reference" "R829"
			(at 0 0 270)
			(layer "F.SilkS")
			(hide yes)
			(effects
				(font
					(size 1.27 1.27)
				)
			)
		)
		(property "Value" "10R3F-GP"
			(at -0.0254 -2.5146 270)
			(unlocked yes)
			(layer "F.Fab")
			(hide yes)
			(effects
				(font
					(size 1.016 1.016)
					(thickness 0.1524)
				)
			)
		)
		(property "Device Type" "R603H22"
			(at -0.0254 -4.0386 270)
			(unlocked yes)
			(layer "F.Fab")
			(hide yes)
			(effects
				(font
					(size 1.016 1.016)
					(thickness 0.1524)
				)
			)
		)
		(duplicate_pad_numbers_are_jumpers no)
		(fp_line
			(start -0.482854 0)
			(end -0.2032 0)
			(stroke
				(width 0.2032)
				(type default)
			)
			(layer "F.SilkS")
		)
		(fp_line
			(start 0.2032 0)
			(end 0.482854 0)
			(stroke
				(width 0.2032)
				(type default)
			)
			(layer "F.SilkS")
		)
		(fp_rect
			(start -0.5842 1.3335)
			(end 0.5842 -1.3335)
			(stroke
				(width 0)
				(type default)
			)
			(fill no)
			(layer "F.CrtYd")
		)
		(fp_rect
			(start -0.5842 1.3335)
			(end 0.5842 -1.3335)
			(stroke
				(width 0)
				(type default)
			)
			(fill no)
			(layer "F.Fab")
		)
		(pad "1" smd custom
			(at 0 -0.762 270)
			(size 0.2159 0.2159)
			(layers "F.Cu" "F.Mask" "F.Paste")
			(net "P3V3_M2_VFB_R")
			(options
				(clearance outline)
				(anchor circle)
			)
			(primitives
				(gr_poly
					(pts
						(arc
							(start -0.3302 -0.4318)
							(mid -0.402042 -0.402042)
							(end -0.4318 -0.3302)
						)
						(arc
							(start -0.4318 0.3302)
							(mid -0.402042 0.402042)
							(end -0.3302 0.4318)
						)
						(arc
							(start 0.3302 0.4318)
							(mid 0.402042 0.402042)
							(end 0.4318 0.3302)
						)
						(arc
							(start 0.4318 -0.3302)
							(mid 0.402042 -0.402042)
							(end 0.3302 -0.4318)
						)
					)
					(width 0)
					(fill yes)
				)
			)
		)
		(pad "2" smd custom
			(at 0 0.762 270)
			(size 0.2159 0.2159)
			(layers "F.Cu" "F.Mask" "F.Paste")
			(net "P3V3_M2")
			(options
				(clearance outline)
				(anchor circle)
			)
			(primitives
				(gr_poly
					(pts
						(arc
							(start -0.3302 -0.4318)
							(mid -0.402042 -0.402042)
							(end -0.4318 -0.3302)
						)
						(arc
							(start -0.4318 0.3302)
							(mid -0.402042 0.402042)
							(end -0.3302 0.4318)
						)
						(arc
							(start 0.3302 0.4318)
							(mid 0.402042 0.402042)
							(end 0.4318 0.3302)
						)
						(arc
							(start 0.4318 -0.3302)
							(mid 0.402042 -0.402042)
							(end 0.3302 -0.4318)
						)
					)
					(width 0)
					(fill yes)
				)
			)
		)
	)
	(footprint ""
		(layer "F.Cu")
		(at 16.023336 -163.5506 -90)
		(property "Reference" "C222"
			(at 0 0 270)
			(layer "F.SilkS")
			(hide yes)
			(effects
				(font
					(size 1.27 1.27)
				)
			)
		)
		(property "Value" "SC1KP50V2KX-1GP"
			(at 1.1811 -2.7051 270)
			(unlocked yes)
			(layer "F.Fab")
			(hide yes)
			(effects
				(font
					(size 1.016 1.016)
					(thickness 0.1524)
				)
			)
		)
		(property "Device Type" "C402H22"
			(at 1.1811 -4.2291 270)
			(unlocked yes)
			(layer "F.Fab")
			(hide yes)
			(effects
				(font
					(size 1.016 1.016)
					(thickness 0.1524)
				)
			)
		)
		(duplicate_pad_numbers_are_jumpers no)
		(fp_rect
			(start -0.4318 0.9525)
			(end 0.4318 -0.9525)
			(stroke
				(width 0)
				(type default)
			)
			(fill no)
			(layer "F.CrtYd")
		)
		(fp_rect
			(start -0.4318 0.9525)
			(end 0.4318 -0.9525)
			(stroke
				(width 0)
				(type default)
			)
			(fill no)
			(layer "F.Fab")
		)
		(pad "1" smd custom
			(at 0 -0.4445 270)
			(size 0.1524 0.1524)
			(layers "F.Cu" "F.Mask" "F.Paste")
			(net "TPS74801_P1V2_STBY_OUT")
			(options
				(clearance outline)
				(anchor circle)
			)
			(primitives
				(gr_poly
					(pts
						(arc
							(start 0.3048 -0.2032)
							(mid 0.275042 -0.275042)
							(end 0.2032 -0.3048)
						)
						(arc
							(start -0.2032 -0.3048)
							(mid -0.275042 -0.275042)
							(end -0.3048 -0.2032)
						)
						(arc
							(start -0.3048 0.2032)
							(mid -0.275042 0.275042)
							(end -0.2032 0.3048)
						)
						(arc
							(start 0.2032 0.3048)
							(mid 0.275042 0.275042)
							(end 0.3048 0.2032)
						)
					)
					(width 0)
					(fill yes)
				)
			)
		)
		(pad "2" smd custom
			(at 0 0.4445 270)
			(size 0.1524 0.1524)
			(layers "F.Cu" "F.Mask" "F.Paste")
			(net "TPS74801_P1V2_STBY_FB")
			(options
				(clearance outline)
				(anchor circle)
			)
			(primitives
				(gr_poly
					(pts
						(arc
							(start 0.3048 -0.2032)
							(mid 0.275042 -0.275042)
							(end 0.2032 -0.3048)
						)
						(arc
							(start -0.2032 -0.3048)
							(mid -0.275042 -0.275042)
							(end -0.3048 -0.2032)
						)
						(arc
							(start -0.3048 0.2032)
							(mid -0.275042 0.275042)
							(end -0.2032 0.3048)
						)
						(arc
							(start 0.2032 0.3048)
							(mid 0.275042 0.275042)
							(end 0.3048 0.2032)
						)
					)
					(width 0)
					(fill yes)
				)
			)
		)
	)
	(footprint ""
		(layer "F.Cu")
		(at 79.487776 -147.894802 90)
		(property "Reference" "R717"
			(at 0 0 90)
			(layer "F.SilkS")
			(hide yes)
			(effects
				(font
					(size 1.27 1.27)
				)
			)
		)
		(property "Value" "0R2J-2-GP"
			(at 0.064008 -3.993896 90)
			(unlocked yes)
			(layer "F.Fab")
			(hide yes)
			(effects
				(font
					(size 1.016 1.016)
					(thickness 0.1524)
				)
			)
		)
		(property "Device Type" "R402H16"
			(at 0.064008 -5.517896 90)
			(unlocked yes)
			(layer "F.Fab")
			(hide yes)
			(effects
				(font
					(size 1.016 1.016)
					(thickness 0.1524)
				)
			)
		)
		(duplicate_pad_numbers_are_jumpers no)
		(fp_line
			(start 0.508 -0.9398)
			(end -0.508 -0.9398)
			(stroke
				(width 0.1524)
				(type default)
			)
			(layer "F.SilkS")
		)
		(fp_line
			(start -0.508 -0.9398)
			(end -0.508 0.9398)
			(stroke
				(width 0.1524)
				(type default)
			)
			(layer "F.SilkS")
		)
		(fp_rect
			(start -0.508 0.9398)
			(end 0.508 -0.9398)
			(stroke
				(width 0)
				(type default)
			)
			(fill no)
			(layer "F.CrtYd")
		)
		(fp_rect
			(start -0.508 0.9398)
			(end 0.508 -0.9398)
			(stroke
				(width 0)
				(type default)
			)
			(fill no)
			(layer "F.Fab")
		)
		(pad "1" smd custom
			(at 0 -0.4445 90)
			(size 0.1397 0.1397)
			(layers "F.Cu" "F.Mask" "F.Paste")
			(net "COMP_TO_BMC_RESET_R")
			(options
				(clearance outline)
				(anchor circle)
			)
			(primitives
				(gr_poly
					(pts
						(arc
							(start -0.1778 -0.2794)
							(mid -0.249642 -0.249642)
							(end -0.2794 -0.1778)
						)
						(arc
							(start -0.2794 0.1778)
							(mid -0.249642 0.249642)
							(end -0.1778 0.2794)
						)
						(arc
							(start 0.1778 0.2794)
							(mid 0.249642 0.249642)
							(end 0.2794 0.1778)
						)
						(arc
							(start 0.2794 -0.1778)
							(mid 0.249642 -0.249642)
							(end 0.1778 -0.2794)
						)
					)
					(width 0)
					(fill yes)
				)
			)
		)
		(pad "2" smd custom
			(at 0 0.4445 90)
			(size 0.1397 0.1397)
			(layers "F.Cu" "F.Mask" "F.Paste")
			(net "COMP_TO_BMC_RESET")
			(options
				(clearance outline)
				(anchor circle)
			)
			(primitives
				(gr_poly
					(pts
						(arc
							(start -0.1778 -0.2794)
							(mid -0.249642 -0.249642)
							(end -0.2794 -0.1778)
						)
						(arc
							(start -0.2794 0.1778)
							(mid -0.249642 0.249642)
							(end -0.1778 0.2794)
						)
						(arc
							(start 0.1778 0.2794)
							(mid 0.249642 0.249642)
							(end 0.2794 0.1778)
						)
						(arc
							(start 0.2794 -0.1778)
							(mid 0.249642 -0.249642)
							(end 0.1778 -0.2794)
						)
					)
					(width 0)
					(fill yes)
				)
			)
		)
	)
)
